# T6G (Grand Teton) — schematic netlist excerpt (pin names and nets, part order shuffled) for the footprints in the layout excerpt that follows; sources: Cadence DE-HDL packaged netlist, KiCad conversion of 04192023_DAF0TMB3IC0_F0TG_MB_C_brd_V02_OCP.brd

J33  SCONN288_DDR506112002KQ  IO  pkg DDR288S_1-1VXC  page 103
  VIN_BULK0  = P12V_MEM_CPU1
  RFU0  = NC
  VIN_MGMT  = P3V3_AUX
  HSCL  = I3C_SPD_DDRF_CPU1_SCL
  HSDA  = I3C_SPD_DDRF_CPU1_SDA
  VSS0  = GND
  DQ0_A  = M_F_CPU1_SA_DQ<0>
  VSS1  = GND
  DQ1_A  = M_F_CPU1_SA_DQ<1>
  VSS2  = GND
  DQS0_A_T  = M_F_CPU1_SA_DQS_DP<0>
  DQS0_A_C  = M_F_CPU1_SA_DQS_DN<0>
  VSS3  = GND
  DQ4_A  = M_F_CPU1_SA_DQ<4>
  VSS4  = GND
  DQ5_A  = M_F_CPU1_SA_DQ<5>
  VSS5  = GND
  DQ8_A  = M_F_CPU1_SA_DQ<8>
  VSS6  = GND
  DQ9_A  = M_F_CPU1_SA_DQ<9>
  VSS7  = GND
  DQS1_A_T  = M_F_CPU1_SA_DQS_DP<1>
  DQS1_A_C  = M_F_CPU1_SA_DQS_DN<1>
  VSS8  = GND
  DQ12_A  = M_F_CPU1_SA_DQ<12>
  VSS9  = GND
  DQ13_A  = M_F_CPU1_SA_DQ<13>
  VSS10  = GND
  DQ16_A  = M_F_CPU1_SA_DQ<16>
  VSS11  = GND
  DQ17_A  = M_F_CPU1_SA_DQ<17>
  VSS12  = GND
  DQS2_A_T  = M_F_CPU1_SA_DQS_DP<2>
  DQS2_A_C  = M_F_CPU1_SA_DQS_DN<2>
  VSS13  = GND
  DQ20_A  = M_F_CPU1_SA_DQ<20>
  VSS14  = GND
  DQ21_A  = M_F_CPU1_SA_DQ<21>
  VSS15  = GND
  DQ24_A  = M_F_CPU1_SA_DQ<24>
  VSS16  = GND
  DQ25_A  = M_F_CPU1_SA_DQ<25>
  VSS17  = GND
  DQS3_A_T  = M_F_CPU1_SA_DQS_DP<3>
  DQS3_A_C  = M_F_CPU1_SA_DQS_DN<3>
  VSS18  = GND
  DQ28_A  = M_F_CPU1_SA_DQ<28>
  VSS19  = GND
  DQ29_A  = M_F_CPU1_SA_DQ<29>
  VSS20  = GND
  CB0_A  = M_F_CPU1_SA_CB<0>
  VSS21  = GND
  CB1_A  = M_F_CPU1_SA_CB<1>
  VSS22  = GND
  DQS4_A_T  = M_F_CPU1_SA_DQS_DP<4>
  DQS4_A_C  = M_F_CPU1_SA_DQS_DN<4>
  VSS23  = GND
  CB4_A  = M_F_CPU1_SA_CB<4>
  VSS24  = GND
  CB5_A  = M_F_CPU1_SA_CB<5>
  VSS25  = GND
  ALERT_N  = M_F_CPU1_ALERT_N
  VSS26  = GND
  CS0_A_N  = M_F_CPU1_SA_CS_N<0>
  VSS27  = GND
  CA0_A  = M_F_CPU1_SA_CA<0>
  VSS28  = GND
  CA2_A  = M_F_CPU1_SA_CA<2>
  VSS29  = GND
  CA4_A  = M_F_CPU1_SA_CA<4>
  VSS30  = GND
  CA6_A  = M_F_CPU1_SA_CA<6>
  VSS31  = GND
  PAR_A  = M_F_CPU1_SA_PAR
  VSS32  = GND
  CA0_B  = M_F_CPU1_SB_CA<0>
  VSS33  = GND
  CA2_B  = M_F_CPU1_SB_CA<2>
  VSS34  = GND
  CA4_B  = M_F_CPU1_SB_CA<4>
  VSS35  = GND
  CA6_B  = M_F_CPU1_SB_CA<6>
  VSS36  = GND
  CS0_B_N  = M_F_CPU1_SB_CS_N<0>
  VSS37  = GND
  \lbd||rsp_a_n\  = M_F_CPU1_SA_RSP<0>
  \lbs||rsp_b_n\  = M_F_CPU1_SB_RSP<0>
  VSS38  = GND
  CB4_B  = M_F_CPU1_SB_CB<4>
  VSS39  = GND
  CB5_B  = M_F_CPU1_SB_CB<5>
  VSS40  = GND
  \dqs9_b_t||tdqs9_b_t||dbi4_b_n\  = M_F_CPU1_SB_DQS_DP<9>
  \dqs9_b_c||tdqs9_b_c\  = M_F_CPU1_SB_DQS_DN<9>
  VSS41  = GND
  CB0_B  = M_F_CPU1_SB_CB<0>
  VSS42  = GND
  CB1_B  = M_F_CPU1_SB_CB<1>
  VSS43  = GND
  DQ0_B  = M_F_CPU1_SB_DQ<0>
  VSS44  = GND
  DQ1_B  = M_F_CPU1_SB_DQ<1>
  VSS45  = GND
  DQS0_B_T  = M_F_CPU1_SB_DQS_DP<0>
  DQS0_B_C  = M_F_CPU1_SB_DQS_DN<0>
  VSS46  = GND
  DQ4_B  = M_F_CPU1_SB_DQ<4>
  VSS47  = GND
  DQ5_B  = M_F_CPU1_SB_DQ<5>
  VSS48  = GND
  DQ8_B  = M_F_CPU1_SB_DQ<8>
  VSS49  = GND
  DQ9_B  = M_F_CPU1_SB_DQ<9>
  VSS50  = GND
  DQS1_B_T  = M_F_CPU1_SB_DQS_DP<1>
  DQS1_B_C  = M_F_CPU1_SB_DQS_DN<1>
  VSS51  = GND
  DQ12_B  = M_F_CPU1_SB_DQ<12>
  VSS52  = GND
  DQ13_B  = M_F_CPU1_SB_DQ<13>
  VSS53  = GND
  DQ16_B  = M_F_CPU1_SB_DQ<16>
  VSS54  = GND
  DQ17_B  = M_F_CPU1_SB_DQ<17>
  VSS55  = GND
  DQS2_B_T  = M_F_CPU1_SB_DQS_DP<2>
  DQS2_B_C  = M_F_CPU1_SB_DQS_DN<2>
  VSS56  = GND
  DQ20_B  = M_F_CPU1_SB_DQ<20>
  VSS57  = GND
  DQ21_B  = M_F_CPU1_SB_DQ<21>
  VSS58  = GND
  DQ24_B  = M_F_CPU1_SB_DQ<24>
  VSS59  = GND
  DQ25_B  = M_F_CPU1_SB_DQ<25>
  VSS60  = GND
  DQS3_B_T  = M_F_CPU1_SB_DQS_DP<3>
  DQS3_B_C  = M_F_CPU1_SB_DQS_DN<3>
  VSS61  = GND
  DQ28_B  = M_F_CPU1_SB_DQ<28>
  VSS62  = GND
  DQ29_B  = M_F_CPU1_SB_DQ<29>
  VSS63  = GND
  RFU1  = NC
  VIN_BULK1  = P12V_MEM_CPU1
  VIN_BULK2  = P12V_MEM_CPU1
  \pwr_good||fail_n\  = PWRGD_CHF_CPU1_DIMM
  HAS  = PD_CHF_CPU1_DIMM_SAA
  RFU2  = NC
  RFU3  = NC
  VSS64  = GND
  DQ2_A  = M_F_CPU1_SA_DQ<2>
  VSS65  = GND
  DQ3_A  = M_F_CPU1_SA_DQ<3>
  VSS66  = GND
  \dqs5_a_c||tdqs5_a_c||dqs5_a_t||tdqs5_a_t\  = M_F_CPU1_SA_DQS_DN<5>
  \dqs5_a_t||tdqs5_a_t\  = M_F_CPU1_SA_DQS_DP<5>
  VSS67  = GND
  DQ6_A  = M_F_CPU1_SA_DQ<6>
  VSS68  = GND
  DQ7_A  = M_F_CPU1_SA_DQ<7>
  VSS69  = GND
  DQ10_A  = M_F_CPU1_SA_DQ<10>
  VSS70  = GND
  DQ11_A  = M_F_CPU1_SA_DQ<11>
  VSS71  = GND
  \dqs6_a_c||tdqs6_a_c||dqs6_a_t||tdqs6_a_t\  = M_F_CPU1_SA_DQS_DN<6>
  \dqs6_a_t||tdqs6_a_t\  = M_F_CPU1_SA_DQS_DP<6>
  VSS72  = GND
  DQ14_A  = M_F_CPU1_SA_DQ<14>
  VSS73  = GND
  DQ15_A  = M_F_CPU1_SA_DQ<15>
  VSS74  = GND
  DQ18_A  = M_F_CPU1_SA_DQ<18>
  VSS75  = GND
  DQ19_A  = M_F_CPU1_SA_DQ<19>
  VSS76  = GND
  \dqs7_a_c||tdqs7_a_c\  = M_F_CPU1_SA_DQS_DN<7>
  \dqs7_a_t||tdqs7_a_t\  = M_F_CPU1_SA_DQS_DP<7>
  VSS77  = GND
  DQ22_A  = M_F_CPU1_SA_DQ<22>
  VSS78  = GND
  DQ23_A  = M_F_CPU1_SA_DQ<23>
  VSS79  = GND
  DQ26_A  = M_F_CPU1_SA_DQ<26>
  VSS80  = GND
  DQ27_A  = M_F_CPU1_SA_DQ<27>
  VSS81  = GND
  \dqs8_a_c||tdqs8_a_c\  = M_F_CPU1_SA_DQS_DN<8>
  \dqs8_a_t||tdqs8_a_t\  = M_F_CPU1_SA_DQS_DP<8>
  VSS82  = GND
  DQ30_A  = M_F_CPU1_SA_DQ<30>
  VSS83  = GND
  DQ31_A  = M_F_CPU1_SA_DQ<31>
  VSS84  = GND
  CB2_A  = M_F_CPU1_SA_CB<2>
  VSS85  = GND
  CB3_A  = M_F_CPU1_SA_CB<3>
  VSS86  = GND
  \dqs9_a_c||tdqs9_a_c\  = M_F_CPU1_SA_DQS_DN<9>
  \dqs9_a_t||tdqs9_a_t\  = M_F_CPU1_SA_DQS_DP<9>
  VSS87  = GND
  CB6_A  = M_F_CPU1_SA_CB<6>
  VSS88  = GND
  CB7_A  = M_F_CPU1_SA_CB<7>
  VSS89  = GND
  RESET_N  = M_F_CPU1_RESET_N
  VSS90  = GND
  CS1_A_N  = M_F_CPU1_SA_CS_N<1>
  VSS91  = GND
  CA1_A  = M_F_CPU1_SA_CA<1>
  VSS92  = GND
  CA3_A  = M_F_CPU1_SA_CA<3>
  VSS93  = GND
  CA5_A  = M_F_CPU1_SA_CA<5>
  VSS94  = GND
  CK_T  = M_F_CPU1_CLK_DP<0>
  CK_C  = M_F_CPU1_CLK_DN<0>
  VSS95  = GND
  RFU4  = NC
  CA1_B  = M_F_CPU1_SB_CA<1>
  VSS96  = GND
  CA3_B  = M_F_CPU1_SB_CA<3>
  VSS97  = GND
  CA5_B  = M_F_CPU1_SB_CA<5>
  VSS98  = GND
  PAR_B  = M_F_CPU1_SB_PAR
  VSS99  = GND
  CS1_B_N  = M_F_CPU1_SB_CS_N<1>
  VSS100  = GND
  RFU5  = NC
  RFU6  = NC
  VSS101  = GND
  CB6_B  = M_F_CPU1_SB_CB<6>
  VSS102  = GND
  CB7_B  = M_F_CPU1_SB_CB<7>
  VSS103  = GND
  DQS4_B_C  = M_F_CPU1_SB_DQS_DN<4>
  DQS4_B_T  = M_F_CPU1_SB_DQS_DP<4>
  VSS104  = GND
  CB2_B  = M_F_CPU1_SB_CB<2>
  VSS105  = GND
  CB3_B  = M_F_CPU1_SB_CB<3>
  VSS106  = GND
  DQ2_B  = M_F_CPU1_SB_DQ<2>
  VSS107  = GND
  DQ3_B  = M_F_CPU1_SB_DQ<3>
  VSS108  = GND
  \dqs5_b_c||tdqs5_b_c\  = M_F_CPU1_SB_DQS_DN<5>
  \dqs5_b_t||tdqs5_b_t\  = M_F_CPU1_SB_DQS_DP<5>
  VSS109  = GND
  DQ6_B  = M_F_CPU1_SB_DQ<6>
  VSS110  = GND
  DQ7_B  = M_F_CPU1_SB_DQ<7>
  VSS111  = GND
  DQ10_B  = M_F_CPU1_SB_DQ<10>
  VSS112  = GND
  DQ11_B  = M_F_CPU1_SB_DQ<11>
  VSS113  = GND
  \dqs6_b_c||tdqs6_b_c\  = M_F_CPU1_SB_DQS_DN<6>
  \dqs6_b_t||tdqs6_b_t\  = M_F_CPU1_SB_DQS_DP<6>
  VSS114  = GND
  DQ14_B  = M_F_CPU1_SB_DQ<14>
  VSS115  = GND
  DQ15_B  = M_F_CPU1_SB_DQ<15>
  VSS116  = GND
  DQ18_B  = M_F_CPU1_SB_DQ<18>
  VSS117  = GND
  DQ19_B  = M_F_CPU1_SB_DQ<19>
  VSS118  = GND
  \dqs7_b_c||tdqs7_b_c\  = M_F_CPU1_SB_DQS_DN<7>
  \dqs7_b_t||tdqs7_b_t\  = M_F_CPU1_SB_DQS_DP<7>
  VSS119  = GND
  DQ22_B  = M_F_CPU1_SB_DQ<22>
  VSS120  = GND
  DQ23_B  = M_F_CPU1_SB_DQ<23>
  VSS121  = GND
  DQ26_B  = M_F_CPU1_SB_DQ<26>
  VSS122  = GND
  DQ27_B  = M_F_CPU1_SB_DQ<27>
  VSS123  = GND
  \dqs8_b_c||tdqs8_b_c\  = M_F_CPU1_SB_DQS_DN<8>
  \dqs8_b_t||tdqs8_b_t\  = M_F_CPU1_SB_DQS_DP<8>
  VSS124  = GND
  DQ30_B  = M_F_CPU1_SB_DQ<30>
  VSS125  = GND
  DQ31_B  = M_F_CPU1_SB_DQ<31>
  VSS126  = GND
  G1  = GND
  G2  = GND
  G3  = GND

(kicad_pcb
	(version 20260206)
	(generator "pcbnew")
	(generator_version "10.0")
	(general
		(thickness 1.6)
		(legacy_teardrops no)
	)
	(paper "A4")
	(title_block
		(title "04192023_DAF0TMB3IC0_F0TG_MB_C_brd_V02_OCP.brd")
		(comment 1 "Grand Teton / footprint 4248 of 8354 (J33), pads 47-92 of 291")
	)
	(layers
		(0 "F.Cu" signal "TOP")
		(4 "In1.Cu" signal "GND")
		(6 "In2.Cu" signal "IN1")
		(8 "In3.Cu" signal "GND1")
		(10 "In4.Cu" signal "IN2")
		(12 "In5.Cu" signal "GND2")
		(14 "In6.Cu" signal "IN3")
		(16 "In7.Cu" signal "GND3")
		(18 "In8.Cu" signal "VCC")
		(20 "In9.Cu" signal "VCC1")
		(22 "In10.Cu" signal "GND4")
		(24 "In11.Cu" signal "IN4")
		(26 "In12.Cu" signal "GND5")
		(28 "In13.Cu" signal "IN5")
		(30 "In14.Cu" signal "GND6")
		(32 "In15.Cu" signal "IN6")
		(34 "In16.Cu" signal "GND7")
		(2 "B.Cu" signal "BOTTOM")
		(9 "F.Adhes" user "F.Adhesive")
		(11 "B.Adhes" user "B.Adhesive")
		(13 "F.Paste" user "Package Geometry/Pastemask Top")
		(15 "B.Paste" user "Package Geometry/Pastemask Bottom")
		(5 "F.SilkS" user "Ref Des/Silkscreen Top")
		(7 "B.SilkS" user "Ref Des/Silkscreen Bottom")
		(1 "F.Mask" user "Board Geometry/Soldermask Top")
		(3 "B.Mask" user "Board Geometry/Soldermask Bottom")
		(17 "Dwgs.User" user "User.Drawings")
		(19 "Cmts.User" user "User.Comments")
		(21 "Eco1.User" user "User.Eco1")
		(23 "Eco2.User" user "User.Eco2")
		(25 "Edge.Cuts" user "Board Geometry/Outline")
		(27 "Margin" user)
		(31 "F.CrtYd" user "Package Geometry/Place Bound Top")
		(29 "B.CrtYd" user "Package Geometry/Place Bound Bottom")
		(35 "F.Fab" user "Ref Des/Assembly Top")
		(33 "B.Fab" user "Ref Des/Assembly Bottom")
	)
	(footprint ""
		(layer "F.Cu")
		(at 19.658076 -255.560322 180)
		(property "Reference" "J33"
			(at -1.25984 -82.079846 0)
			(unlocked yes)
			(layer "F.SilkS")
			(effects
				(font
					(size 0.7874 0.5842)
					(thickness 0.1524)
				)
			)
		)
		(property "Value" ""
			(at 0 0 180)
			(layer "F.Fab")
			(effects
				(font
					(size 1.27 1.27)
				)
			)
		)
		(duplicate_pad_numbers_are_jumpers no)
		(pad "47" smd rect
			(at -2.050034 -24.224996 90)
			(size 0.519938 1.4986)
			(layers "F.Cu" "F.Mask" "F.Paste")
			(net "M_F_CPU1_SA_DQ<28>")
		)
		(pad "48" smd rect
			(at -2.050034 -23.375112 90)
			(size 0.519938 1.4986)
			(layers "F.Cu" "F.Mask" "F.Paste")
			(net "GND")
		)
		(pad "49" smd rect
			(at -2.050034 -22.524974 90)
			(size 0.519938 1.4986)
			(layers "F.Cu" "F.Mask" "F.Paste")
			(net "M_F_CPU1_SA_DQ<29>")
		)
		(pad "50" smd rect
			(at -2.050034 -21.67509 90)
			(size 0.519938 1.4986)
			(layers "F.Cu" "F.Mask" "F.Paste")
			(net "GND")
		)
		(pad "51" smd rect
			(at -2.050034 -20.824952 90)
			(size 0.519938 1.4986)
			(layers "F.Cu" "F.Mask" "F.Paste")
			(net "M_F_CPU1_SA_CB<0>")
		)
		(pad "52" smd rect
			(at -2.050034 -19.975068 90)
			(size 0.519938 1.4986)
			(layers "F.Cu" "F.Mask" "F.Paste")
			(net "GND")
		)
		(pad "53" smd rect
			(at -2.050034 -19.12493 90)
			(size 0.519938 1.4986)
			(layers "F.Cu" "F.Mask" "F.Paste")
			(net "M_F_CPU1_SA_CB<1>")
		)
		(pad "54" smd rect
			(at -2.050034 -18.275046 90)
			(size 0.519938 1.4986)
			(layers "F.Cu" "F.Mask" "F.Paste")
			(net "GND")
		)
		(pad "55" smd rect
			(at -2.050034 -17.424908 90)
			(size 0.519938 1.4986)
			(layers "F.Cu" "F.Mask" "F.Paste")
			(net "M_F_CPU1_SA_DQS_DP<4>")
		)
		(pad "56" smd rect
			(at -2.050034 -16.575024 90)
			(size 0.519938 1.4986)
			(layers "F.Cu" "F.Mask" "F.Paste")
			(net "M_F_CPU1_SA_DQS_DN<4>")
		)
		(pad "57" smd rect
			(at -2.050034 -15.724886 90)
			(size 0.519938 1.4986)
			(layers "F.Cu" "F.Mask" "F.Paste")
			(net "GND")
		)
		(pad "58" smd rect
			(at -2.050034 -14.875002 90)
			(size 0.519938 1.4986)
			(layers "F.Cu" "F.Mask" "F.Paste")
			(net "M_F_CPU1_SA_CB<4>")
		)
		(pad "59" smd rect
			(at -2.050034 -14.025118 90)
			(size 0.519938 1.4986)
			(layers "F.Cu" "F.Mask" "F.Paste")
			(net "GND")
		)
		(pad "60" smd rect
			(at -2.050034 -13.17498 90)
			(size 0.519938 1.4986)
			(layers "F.Cu" "F.Mask" "F.Paste")
			(net "M_F_CPU1_SA_CB<5>")
		)
		(pad "61" smd rect
			(at -2.050034 -12.325096 90)
			(size 0.519938 1.4986)
			(layers "F.Cu" "F.Mask" "F.Paste")
			(net "GND")
		)
		(pad "62" smd rect
			(at -2.050034 -11.474958 90)
			(size 0.519938 1.4986)
			(layers "F.Cu" "F.Mask" "F.Paste")
			(net "M_F_CPU1_ALERT_N")
		)
		(pad "63" smd rect
			(at -2.050034 -10.625074 90)
			(size 0.519938 1.4986)
			(layers "F.Cu" "F.Mask" "F.Paste")
			(net "GND")
		)
		(pad "64" smd rect
			(at -2.050034 -9.774936 90)
			(size 0.519938 1.4986)
			(layers "F.Cu" "F.Mask" "F.Paste")
			(net "M_F_CPU1_SA_CS_N<0>")
		)
		(pad "65" smd rect
			(at -2.050034 -8.925052 90)
			(size 0.519938 1.4986)
			(layers "F.Cu" "F.Mask" "F.Paste")
			(net "GND")
		)
		(pad "66" smd rect
			(at -2.050034 -8.074914 90)
			(size 0.519938 1.4986)
			(layers "F.Cu" "F.Mask" "F.Paste")
			(net "M_F_CPU1_SA_CA<0>")
		)
		(pad "67" smd rect
			(at -2.050034 -7.22503 90)
			(size 0.519938 1.4986)
			(layers "F.Cu" "F.Mask" "F.Paste")
			(net "GND")
		)
		(pad "68" smd rect
			(at -2.050034 -6.374892 90)
			(size 0.519938 1.4986)
			(layers "F.Cu" "F.Mask" "F.Paste")
			(net "M_F_CPU1_SA_CA<2>")
		)
		(pad "69" smd rect
			(at -2.050034 -5.525008 90)
			(size 0.519938 1.4986)
			(layers "F.Cu" "F.Mask" "F.Paste")
			(net "GND")
		)
		(pad "70" smd rect
			(at -2.050034 -4.675124 90)
			(size 0.519938 1.4986)
			(layers "F.Cu" "F.Mask" "F.Paste")
			(net "M_F_CPU1_SA_CA<4>")
		)
		(pad "71" smd rect
			(at -2.050034 -3.824986 90)
			(size 0.519938 1.4986)
			(layers "F.Cu" "F.Mask" "F.Paste")
			(net "GND")
		)
		(pad "72" smd rect
			(at -2.050034 -2.975102 90)
			(size 0.519938 1.4986)
			(layers "F.Cu" "F.Mask" "F.Paste")
			(net "M_F_CPU1_SA_CA<6>")
		)
		(pad "73" smd rect
			(at -2.050034 -2.124964 90)
			(size 0.519938 1.4986)
			(layers "F.Cu" "F.Mask" "F.Paste")
			(net "GND")
		)
		(pad "74" smd rect
			(at -2.050034 -1.27508 90)
			(size 0.519938 1.4986)
			(layers "F.Cu" "F.Mask" "F.Paste")
			(net "M_F_CPU1_SA_PAR")
		)
		(pad "75" smd rect
			(at -2.050034 -0.424942 90)
			(size 0.519938 1.4986)
			(layers "F.Cu" "F.Mask" "F.Paste")
			(net "GND")
		)
		(pad "76" smd rect
			(at -2.050034 5.525008 90)
			(size 0.519938 1.4986)
			(layers "F.Cu" "F.Mask" "F.Paste")
			(net "M_F_CPU1_SB_CA<0>")
		)
		(pad "77" smd rect
			(at -2.050034 6.374892 90)
			(size 0.519938 1.4986)
			(layers "F.Cu" "F.Mask" "F.Paste")
			(net "GND")
		)
		(pad "78" smd rect
			(at -2.050034 7.22503 90)
			(size 0.519938 1.4986)
			(layers "F.Cu" "F.Mask" "F.Paste")
			(net "M_F_CPU1_SB_CA<2>")
		)
		(pad "79" smd rect
			(at -2.050034 8.074914 90)
			(size 0.519938 1.4986)
			(layers "F.Cu" "F.Mask" "F.Paste")
			(net "GND")
		)
		(pad "80" smd rect
			(at -2.050034 8.925052 90)
			(size 0.519938 1.4986)
			(layers "F.Cu" "F.Mask" "F.Paste")
			(net "M_F_CPU1_SB_CA<4>")
		)
		(pad "81" smd rect
			(at -2.050034 9.774936 90)
			(size 0.519938 1.4986)
			(layers "F.Cu" "F.Mask" "F.Paste")
			(net "GND")
		)
		(pad "82" smd rect
			(at -2.050034 10.625074 90)
			(size 0.519938 1.4986)
			(layers "F.Cu" "F.Mask" "F.Paste")
			(net "M_F_CPU1_SB_CA<6>")
		)
		(pad "83" smd rect
			(at -2.050034 11.474958 90)
			(size 0.519938 1.4986)
			(layers "F.Cu" "F.Mask" "F.Paste")
			(net "GND")
		)
		(pad "84" smd rect
			(at -2.050034 12.325096 90)
			(size 0.519938 1.4986)
			(layers "F.Cu" "F.Mask" "F.Paste")
			(net "M_F_CPU1_SB_CS_N<0>")
		)
		(pad "85" smd rect
			(at -2.050034 13.17498 90)
			(size 0.519938 1.4986)
			(layers "F.Cu" "F.Mask" "F.Paste")
			(net "GND")
		)
		(pad "86" smd rect
			(at -2.050034 14.025118 90)
			(size 0.519938 1.4986)
			(layers "F.Cu" "F.Mask" "F.Paste")
			(net "M_F_CPU1_SA_RSP<0>")
		)
		(pad "87" smd rect
			(at -2.050034 14.875002 90)
			(size 0.519938 1.4986)
			(layers "F.Cu" "F.Mask" "F.Paste")
			(net "M_F_CPU1_SB_RSP<0>")
		)
		(pad "88" smd rect
			(at -2.050034 15.724886 90)
			(size 0.519938 1.4986)
			(layers "F.Cu" "F.Mask" "F.Paste")
			(net "GND")
		)
		(pad "89" smd rect
			(at -2.050034 16.575024 90)
			(size 0.519938 1.4986)
			(layers "F.Cu" "F.Mask" "F.Paste")
			(net "M_F_CPU1_SB_CB<4>")
		)
		(pad "90" smd rect
			(at -2.050034 17.424908 90)
			(size 0.519938 1.4986)
			(layers "F.Cu" "F.Mask" "F.Paste")
			(net "GND")
		)
		(pad "91" smd rect
			(at -2.050034 18.275046 90)
			(size 0.519938 1.4986)
			(layers "F.Cu" "F.Mask" "F.Paste")
			(net "M_F_CPU1_SB_CB<5>")
		)
		(pad "92" smd rect
			(at -2.050034 19.12493 90)
			(size 0.519938 1.4986)
			(layers "F.Cu" "F.Mask" "F.Paste")
			(net "GND")
		)
	)
)
